# T6G (Grand Teton) — schematic netlist excerpt (pin names and nets, part order shuffled) for the footprints in the layout excerpt that follows; sources: Cadence DE-HDL packaged netlist, KiCad conversion of 04192023_DAF0TMB3IC0_F0TG_MB_C_brd_V02_OCP.brd

D49  Q_LED  IC  pkg SMLF  page 166 : A = P5V_STBY_PWR_LED ; C = GND
R8286  Q_RES  1K 1% EMPTY  pkg 0402LF  page 193 : A = SVID_PVDDCR_CPU0_P0_SVTO ; B = GND
R1397  Q_RES  1K 1% EMPTY  pkg 0201LF  page 287 : A = P1V8_CPU0_RT_1D ; B = RXDET_BYP_RT_CPU0_P1

(kicad_pcb
	(version 20260206)
	(generator "pcbnew")
	(generator_version "10.0")
	(general
		(thickness 1.6)
		(legacy_teardrops no)
	)
	(paper "A4")
	(title_block
		(title "04192023_DAF0TMB3IC0_F0TG_MB_C_brd_V02_OCP.brd")
		(comment 1 "Grand Teton / footprints 2826-2828 of 8354")
	)
	(layers
		(0 "F.Cu" signal "TOP")
		(4 "In1.Cu" signal "GND")
		(6 "In2.Cu" signal "IN1")
		(8 "In3.Cu" signal "GND1")
		(10 "In4.Cu" signal "IN2")
		(12 "In5.Cu" signal "GND2")
		(14 "In6.Cu" signal "IN3")
		(16 "In7.Cu" signal "GND3")
		(18 "In8.Cu" signal "VCC")
		(20 "In9.Cu" signal "VCC1")
		(22 "In10.Cu" signal "GND4")
		(24 "In11.Cu" signal "IN4")
		(26 "In12.Cu" signal "GND5")
		(28 "In13.Cu" signal "IN5")
		(30 "In14.Cu" signal "GND6")
		(32 "In15.Cu" signal "IN6")
		(34 "In16.Cu" signal "GND7")
		(2 "B.Cu" signal "BOTTOM")
		(9 "F.Adhes" user "F.Adhesive")
		(11 "B.Adhes" user "B.Adhesive")
		(13 "F.Paste" user "Package Geometry/Pastemask Top")
		(15 "B.Paste" user "Package Geometry/Pastemask Bottom")
		(5 "F.SilkS" user "Ref Des/Silkscreen Top")
		(7 "B.SilkS" user "Ref Des/Silkscreen Bottom")
		(1 "F.Mask" user "Board Geometry/Soldermask Top")
		(3 "B.Mask" user "Board Geometry/Soldermask Bottom")
		(17 "Dwgs.User" user "User.Drawings")
		(19 "Cmts.User" user "User.Comments")
		(21 "Eco1.User" user "User.Eco1")
		(23 "Eco2.User" user "User.Eco2")
		(25 "Edge.Cuts" user "Board Geometry/Outline")
		(27 "Margin" user)
		(31 "F.CrtYd" user "Package Geometry/Place Bound Top")
		(29 "B.CrtYd" user "Package Geometry/Place Bound Bottom")
		(35 "F.Fab" user "Ref Des/Assembly Top")
		(33 "B.Fab" user "Ref Des/Assembly Bottom")
	)
	(footprint ""
		(layer "F.Cu")
		(at 345.8337 -15.924276 90)
		(property "Reference" "D49"
			(at -3.1496 0.230632 90)
			(unlocked yes)
			(layer "F.SilkS")
			(effects
				(font
					(size 0.7874 0.5842)
					(thickness 0.1524)
				)
				(justify left)
			)
		)
		(property "Value" ""
			(at 0 0 90)
			(layer "F.Fab")
			(effects
				(font
					(size 1.27 1.27)
				)
			)
		)
		(duplicate_pad_numbers_are_jumpers no)
		(fp_line
			(start 1.16078 -0.4826)
			(end 1.16078 0.4826)
			(stroke
				(width 0.1524)
				(type default)
			)
			(layer "F.SilkS")
		)
		(fp_line
			(start 1.03378 -0.4826)
			(end 1.03378 0.4826)
			(stroke
				(width 0.1524)
				(type default)
			)
			(layer "F.SilkS")
		)
		(fp_line
			(start 0.90678 -0.4826)
			(end 0.90678 0.4826)
			(stroke
				(width 0.1524)
				(type default)
			)
			(layer "F.SilkS")
		)
		(fp_line
			(start -0.64008 -0.4826)
			(end 1.16078 -0.4826)
			(stroke
				(width 0.1524)
				(type default)
			)
			(layer "F.SilkS")
		)
		(fp_line
			(start -0.79248 -0.4826)
			(end 1.03378 -0.4826)
			(stroke
				(width 0.1524)
				(type default)
			)
			(layer "F.SilkS")
		)
		(fp_line
			(start -0.89408 -0.4826)
			(end 0.90678 -0.4826)
			(stroke
				(width 0.1524)
				(type default)
			)
			(layer "F.SilkS")
		)
		(fp_line
			(start 1.16078 0.4826)
			(end -0.64008 0.4826)
			(stroke
				(width 0.1524)
				(type default)
			)
			(layer "F.SilkS")
		)
		(fp_line
			(start 1.03378 0.4826)
			(end -0.79248 0.4826)
			(stroke
				(width 0.1524)
				(type default)
			)
			(layer "F.SilkS")
		)
		(fp_line
			(start 0.90678 0.4826)
			(end -0.90678 0.4826)
			(stroke
				(width 0.1524)
				(type default)
			)
			(layer "F.SilkS")
		)
		(fp_line
			(start -0.90678 0.4826)
			(end -0.90678 -0.4699)
			(stroke
				(width 0.1524)
				(type default)
			)
			(layer "F.SilkS")
		)
		(fp_line
			(start 0.499872 -0.249936)
			(end 0.499872 0.249936)
			(stroke
				(width 0.1)
				(type default)
			)
			(layer "F.Fab")
		)
		(fp_line
			(start -0.499872 -0.249936)
			(end 0.499872 -0.249936)
			(stroke
				(width 0.1)
				(type default)
			)
			(layer "F.Fab")
		)
		(fp_line
			(start 0.499872 0.249936)
			(end -0.499872 0.249936)
			(stroke
				(width 0.1)
				(type default)
			)
			(layer "F.Fab")
		)
		(fp_line
			(start -0.499872 0.249936)
			(end -0.499872 -0.249936)
			(stroke
				(width 0.1)
				(type default)
			)
			(layer "F.Fab")
		)
		(pad "A" smd rect
			(at -0.47498 0 90)
			(size 0.6096 0.7112)
			(layers "F.Cu" "F.Mask" "F.Paste")
			(net "P5V_STBY_PWR_LED")
		)
		(pad "C" smd rect
			(at 0.47498 0 90)
			(size 0.6096 0.7112)
			(layers "F.Cu" "F.Mask" "F.Paste")
			(net "GND")
		)
	)
	(footprint ""
		(layer "F.Cu")
		(at 360.190542 -399.034)
		(property "Reference" "R1397"
			(at 0 0 0)
			(layer "F.SilkS")
			(hide yes)
			(effects
				(font
					(size 1.27 1.27)
				)
			)
		)
		(property "Value" ""
			(at 0 0 0)
			(layer "F.Fab")
			(effects
				(font
					(size 1.27 1.27)
				)
			)
		)
		(duplicate_pad_numbers_are_jumpers no)
		(fp_line
			(start -0.32512 -0.175006)
			(end 0.32512 -0.175006)
			(stroke
				(width 0.1)
				(type default)
			)
			(layer "F.Fab")
		)
		(fp_line
			(start -0.32512 0.175006)
			(end -0.32512 -0.175006)
			(stroke
				(width 0.1)
				(type default)
			)
			(layer "F.Fab")
		)
		(fp_line
			(start 0.32512 -0.175006)
			(end 0.32512 0.175006)
			(stroke
				(width 0.1)
				(type default)
			)
			(layer "F.Fab")
		)
		(fp_line
			(start 0.32512 0.175006)
			(end -0.32512 0.175006)
			(stroke
				(width 0.1)
				(type default)
			)
			(layer "F.Fab")
		)
		(pad "1" smd rect
			(at -0.2667 0)
			(size 0.3048 0.381)
			(layers "F.Cu" "F.Mask" "F.Paste")
			(net "P1V8_CPU0_RT_1D")
		)
		(pad "2" smd rect
			(at 0.2667 0 180)
			(size 0.3048 0.381)
			(layers "F.Cu" "F.Mask" "F.Paste")
			(net "RXDET_BYP_RT_CPU0_P1")
		)
	)
	(footprint ""
		(layer "F.Cu")
		(at 370.905278 -146.552158 180)
		(property "Reference" "R8286"
			(at 0 0 180)
			(layer "F.SilkS")
			(hide yes)
			(effects
				(font
					(size 1.27 1.27)
				)
			)
		)
		(property "Value" ""
			(at 0 0 180)
			(layer "F.Fab")
			(effects
				(font
					(size 1.27 1.27)
				)
			)
		)
		(duplicate_pad_numbers_are_jumpers no)
		(fp_line
			(start 0.7874 0.4064)
			(end -0.7874 0.4064)
			(stroke
				(width 0.1524)
				(type default)
			)
			(layer "F.SilkS")
		)
		(fp_line
			(start 0.7874 -0.4064)
			(end 0.7874 0.4064)
			(stroke
				(width 0.1524)
				(type default)
			)
			(layer "F.SilkS")
		)
		(fp_line
			(start -0.7874 0.4064)
			(end -0.7874 -0.4064)
			(stroke
				(width 0.1524)
				(type default)
			)
			(layer "F.SilkS")
		)
		(fp_line
			(start -0.7874 -0.4064)
			(end 0.7874 -0.4064)
			(stroke
				(width 0.1524)
				(type default)
			)
			(layer "F.SilkS")
		)
		(fp_line
			(start 0.67945 0.3048)
			(end 0.120396 0.3048)
			(stroke
				(width 0.1)
				(type default)
			)
			(layer "F.Fab")
		)
		(fp_line
			(start 0.67945 -0.3048)
			(end 0.67945 0.3048)
			(stroke
				(width 0.1)
				(type default)
			)
			(layer "F.Fab")
		)
		(fp_line
			(start 0.12065 -0.2794)
			(end 0.12065 -0.3048)
			(stroke
				(width 0.1)
				(type default)
			)
			(layer "F.Fab")
		)
		(fp_line
			(start 0.12065 -0.3048)
			(end 0.67945 -0.3048)
			(stroke
				(width 0.1)
				(type default)
			)
			(layer "F.Fab")
		)
		(fp_line
			(start 0.120396 0.3048)
			(end 0.120396 0.2794)
			(stroke
				(width 0.1)
				(type default)
			)
			(layer "F.Fab")
		)
		(fp_line
			(start 0.120396 0.2794)
			(end -0.12065 0.2794)
			(stroke
				(width 0.1)
				(type default)
			)
			(layer "F.Fab")
		)
		(fp_line
			(start -0.12065 0.3048)
			(end -0.67945 0.3048)
			(stroke
				(width 0.1)
				(type default)
			)
			(layer "F.Fab")
		)
		(fp_line
			(start -0.12065 0.2794)
			(end -0.12065 0.3048)
			(stroke
				(width 0.1)
				(type default)
			)
			(layer "F.Fab")
		)
		(fp_line
			(start -0.12065 -0.2794)
			(end 0.12065 -0.2794)
			(stroke
				(width 0.1)
				(type default)
			)
			(layer "F.Fab")
		)
		(fp_line
			(start -0.12065 -0.305054)
			(end -0.12065 -0.2794)
			(stroke
				(width 0.1)
				(type default)
			)
			(layer "F.Fab")
		)
		(fp_line
			(start -0.67945 0.3048)
			(end -0.67945 -0.305054)
			(stroke
				(width 0.1)
				(type default)
			)
			(layer "F.Fab")
		)
		(fp_line
			(start -0.67945 -0.305054)
			(end -0.12065 -0.305054)
			(stroke
				(width 0.1)
				(type default)
			)
			(layer "F.Fab")
		)
		(pad "1" smd circle
			(at -0.40005 0 180)
			(size 0 0)
			(layers "F.Cu" "F.Mask" "F.Paste")
			(net "SVID_PVDDCR_CPU0_P0_SVTO")
		)
		(pad "2" smd circle
			(at 0.40005 0 180)
			(size 0 0)
			(layers "F.Cu" "F.Mask" "F.Paste")
			(net "GND")
		)
	)
)
